# T6G (Grand Teton) — schematic netlist excerpt (pin names and nets, part order shuffled) for the footprints in the layout excerpt that follows; sources: Cadence DE-HDL packaged netlist, KiCad conversion of 04192023_DAF0TMB3IC0_F0TG_MB_C_brd_V02_OCP.brd

C636  Q_CAP  22UF 4V 20% X6S  pkg C0402  page 290 : A = P0V9_CPU0_RT_2D ; B = GND
C6033  Q_CAP  0.01UF 50V 10% X7R  pkg C0402  page 177 : A = P1V2_CPU0_USB_DVDD12 ; B = GND

(kicad_pcb
	(version 20260206)
	(generator "pcbnew")
	(generator_version "10.0")
	(general
		(thickness 1.6)
		(legacy_teardrops no)
	)
	(paper "A4")
	(title_block
		(title "04192023_DAF0TMB3IC0_F0TG_MB_C_brd_V02_OCP.brd")
		(comment 1 "Grand Teton / footprints 8054-8055 of 8354")
	)
	(layers
		(0 "F.Cu" signal "TOP")
		(4 "In1.Cu" signal "GND")
		(6 "In2.Cu" signal "IN1")
		(8 "In3.Cu" signal "GND1")
		(10 "In4.Cu" signal "IN2")
		(12 "In5.Cu" signal "GND2")
		(14 "In6.Cu" signal "IN3")
		(16 "In7.Cu" signal "GND3")
		(18 "In8.Cu" signal "VCC")
		(20 "In9.Cu" signal "VCC1")
		(22 "In10.Cu" signal "GND4")
		(24 "In11.Cu" signal "IN4")
		(26 "In12.Cu" signal "GND5")
		(28 "In13.Cu" signal "IN5")
		(30 "In14.Cu" signal "GND6")
		(32 "In15.Cu" signal "IN6")
		(34 "In16.Cu" signal "GND7")
		(2 "B.Cu" signal "BOTTOM")
		(9 "F.Adhes" user "F.Adhesive")
		(11 "B.Adhes" user "B.Adhesive")
		(13 "F.Paste" user "Package Geometry/Pastemask Top")
		(15 "B.Paste" user "Package Geometry/Pastemask Bottom")
		(5 "F.SilkS" user "Ref Des/Silkscreen Top")
		(7 "B.SilkS" user "Ref Des/Silkscreen Bottom")
		(1 "F.Mask" user "Board Geometry/Soldermask Top")
		(3 "B.Mask" user "Board Geometry/Soldermask Bottom")
		(17 "Dwgs.User" user "User.Drawings")
		(19 "Cmts.User" user "User.Comments")
		(21 "Eco1.User" user "User.Eco1")
		(23 "Eco2.User" user "User.Eco2")
		(25 "Edge.Cuts" user "Board Geometry/Outline")
		(27 "Margin" user)
		(31 "F.CrtYd" user "Package Geometry/Place Bound Top")
		(29 "B.CrtYd" user "Package Geometry/Place Bound Bottom")
		(35 "F.Fab" user "Ref Des/Assembly Top")
		(33 "B.Fab" user "Ref Des/Assembly Bottom")
	)
	(footprint ""
		(layer "B.Cu")
		(at 346.71889 -398.942052 90)
		(property "Reference" "C636"
			(at 0 0 90)
			(layer "B.SilkS")
			(hide yes)
			(effects
				(font
					(size 1.27 1.27)
				)
				(justify mirror)
			)
		)
		(property "Value" ""
			(at 0 0 90)
			(layer "B.Fab")
			(effects
				(font
					(size 1.27 1.27)
				)
				(justify mirror)
			)
		)
		(duplicate_pad_numbers_are_jumpers no)
		(fp_line
			(start 0.7874 -0.4064)
			(end -0.7874 -0.4064)
			(stroke
				(width 0.1524)
				(type default)
			)
			(layer "B.SilkS")
		)
		(fp_line
			(start -0.7874 -0.4064)
			(end -0.7874 0.4064)
			(stroke
				(width 0.1524)
				(type default)
			)
			(layer "B.SilkS")
		)
		(fp_line
			(start 0.7874 0.4064)
			(end 0.7874 -0.4064)
			(stroke
				(width 0.1524)
				(type default)
			)
			(layer "B.SilkS")
		)
		(fp_line
			(start -0.7874 0.4064)
			(end 0.7874 0.4064)
			(stroke
				(width 0.1524)
				(type default)
			)
			(layer "B.SilkS")
		)
		(fp_line
			(start 0.67945 -0.305054)
			(end 0.12065 -0.305054)
			(stroke
				(width 0.1)
				(type default)
			)
			(layer "B.Fab")
		)
		(fp_line
			(start 0.12065 -0.305054)
			(end 0.12065 -0.2794)
			(stroke
				(width 0.1)
				(type default)
			)
			(layer "B.Fab")
		)
		(fp_line
			(start -0.12065 -0.3048)
			(end -0.67945 -0.3048)
			(stroke
				(width 0.1)
				(type default)
			)
			(layer "B.Fab")
		)
		(fp_line
			(start -0.67945 -0.3048)
			(end -0.67945 0.3048)
			(stroke
				(width 0.1)
				(type default)
			)
			(layer "B.Fab")
		)
		(fp_line
			(start 0.12065 -0.2794)
			(end -0.12065 -0.2794)
			(stroke
				(width 0.1)
				(type default)
			)
			(layer "B.Fab")
		)
		(fp_line
			(start -0.12065 -0.2794)
			(end -0.12065 -0.3048)
			(stroke
				(width 0.1)
				(type default)
			)
			(layer "B.Fab")
		)
		(fp_line
			(start 0.12065 0.2794)
			(end 0.12065 0.3048)
			(stroke
				(width 0.1)
				(type default)
			)
			(layer "B.Fab")
		)
		(fp_line
			(start -0.120396 0.2794)
			(end 0.12065 0.2794)
			(stroke
				(width 0.1)
				(type default)
			)
			(layer "B.Fab")
		)
		(fp_line
			(start 0.67945 0.3048)
			(end 0.67945 -0.305054)
			(stroke
				(width 0.1)
				(type default)
			)
			(layer "B.Fab")
		)
		(fp_line
			(start 0.12065 0.3048)
			(end 0.67945 0.3048)
			(stroke
				(width 0.1)
				(type default)
			)
			(layer "B.Fab")
		)
		(fp_line
			(start -0.120396 0.3048)
			(end -0.120396 0.2794)
			(stroke
				(width 0.1)
				(type default)
			)
			(layer "B.Fab")
		)
		(fp_line
			(start -0.67945 0.3048)
			(end -0.120396 0.3048)
			(stroke
				(width 0.1)
				(type default)
			)
			(layer "B.Fab")
		)
		(pad "1" smd circle
			(at 0.40005 0 270)
			(size 0 0)
			(layers "B.Cu" "B.Mask" "B.Paste")
			(net "P0V9_CPU0_RT_2D")
		)
		(pad "2" smd circle
			(at -0.40005 0 270)
			(size 0 0)
			(layers "B.Cu" "B.Mask" "B.Paste")
			(net "GND")
		)
	)
	(footprint ""
		(layer "B.Cu")
		(at 132.490972 -41.007792 90)
		(property "Reference" "C6033"
			(at 0 0 90)
			(layer "B.SilkS")
			(hide yes)
			(effects
				(font
					(size 1.27 1.27)
				)
				(justify mirror)
			)
		)
		(property "Value" ""
			(at 0 0 90)
			(layer "B.Fab")
			(effects
				(font
					(size 1.27 1.27)
				)
				(justify mirror)
			)
		)
		(duplicate_pad_numbers_are_jumpers no)
		(fp_line
			(start 0.7874 -0.4064)
			(end -0.7874 -0.4064)
			(stroke
				(width 0.1524)
				(type default)
			)
			(layer "B.SilkS")
		)
		(fp_line
			(start -0.7874 -0.4064)
			(end -0.7874 0.4064)
			(stroke
				(width 0.1524)
				(type default)
			)
			(layer "B.SilkS")
		)
		(fp_line
			(start 0.7874 0.4064)
			(end 0.7874 -0.4064)
			(stroke
				(width 0.1524)
				(type default)
			)
			(layer "B.SilkS")
		)
		(fp_line
			(start -0.7874 0.4064)
			(end 0.7874 0.4064)
			(stroke
				(width 0.1524)
				(type default)
			)
			(layer "B.SilkS")
		)
		(fp_line
			(start 0.67945 -0.305054)
			(end 0.12065 -0.305054)
			(stroke
				(width 0.1)
				(type default)
			)
			(layer "B.Fab")
		)
		(fp_line
			(start 0.12065 -0.305054)
			(end 0.12065 -0.2794)
			(stroke
				(width 0.1)
				(type default)
			)
			(layer "B.Fab")
		)
		(fp_line
			(start -0.12065 -0.3048)
			(end -0.67945 -0.3048)
			(stroke
				(width 0.1)
				(type default)
			)
			(layer "B.Fab")
		)
		(fp_line
			(start -0.67945 -0.3048)
			(end -0.67945 0.3048)
			(stroke
				(width 0.1)
				(type default)
			)
			(layer "B.Fab")
		)
		(fp_line
			(start 0.12065 -0.2794)
			(end -0.12065 -0.2794)
			(stroke
				(width 0.1)
				(type default)
			)
			(layer "B.Fab")
		)
		(fp_line
			(start -0.12065 -0.2794)
			(end -0.12065 -0.3048)
			(stroke
				(width 0.1)
				(type default)
			)
			(layer "B.Fab")
		)
		(fp_line
			(start 0.12065 0.2794)
			(end 0.12065 0.3048)
			(stroke
				(width 0.1)
				(type default)
			)
			(layer "B.Fab")
		)
		(fp_line
			(start -0.120396 0.2794)
			(end 0.12065 0.2794)
			(stroke
				(width 0.1)
				(type default)
			)
			(layer "B.Fab")
		)
		(fp_line
			(start 0.67945 0.3048)
			(end 0.67945 -0.305054)
			(stroke
				(width 0.1)
				(type default)
			)
			(layer "B.Fab")
		)
		(fp_line
			(start 0.12065 0.3048)
			(end 0.67945 0.3048)
			(stroke
				(width 0.1)
				(type default)
			)
			(layer "B.Fab")
		)
		(fp_line
			(start -0.120396 0.3048)
			(end -0.120396 0.2794)
			(stroke
				(width 0.1)
				(type default)
			)
			(layer "B.Fab")
		)
		(fp_line
			(start -0.67945 0.3048)
			(end -0.120396 0.3048)
			(stroke
				(width 0.1)
				(type default)
			)
			(layer "B.Fab")
		)
		(pad "1" smd circle
			(at 0.40005 0 270)
			(size 0 0)
			(layers "B.Cu" "B.Mask" "B.Paste")
			(net "P1V2_CPU0_USB_DVDD12")
		)
		(pad "2" smd circle
			(at -0.40005 0 270)
			(size 0 0)
			(layers "B.Cu" "B.Mask" "B.Paste")
			(net "GND")
		)
	)
)
